# BASEBOARD_FAB2 (Tioga Pass) — schematic netlist excerpt (pin names and nets, part order shuffled) for the footprints in the layout excerpt that follows; sources: Cadence DE-HDL packaged netlist, KiCad conversion of Wiwynn_Tioga_Pass_MB.brd

C8T10  CAP_A  47UF 4V 20% X5R  pkg 0603V  page 225 : A = PVDDQ_GHJ ; B = GND
C6R8  CAP  10UF 16V 10% X6S  pkg 0805  page 214 : A = VR_FET_SW_P12V_STBY_PVCCIN_CPU0 ; B = GND
C9P25  CAP  10UF 16V 10% X6S  pkg 0805  page 207 : A = VR_FET_SW_P12V_STBY_PVCCIN_CPU1 ; B = GND

(kicad_pcb
	(version 20260206)
	(generator "pcbnew")
	(generator_version "10.0")
	(general
		(thickness 1.6)
		(legacy_teardrops no)
	)
	(paper "A4")
	(title_block
		(title "Wiwynn_Tioga_Pass_MB.brd")
		(comment 1 "Tioga Pass / footprints 2966-2968 of 4770")
	)
	(layers
		(0 "F.Cu" signal "TOP")
		(4 "In1.Cu" signal "L2GND")
		(6 "In2.Cu" signal "L3")
		(8 "In3.Cu" signal "L4GND")
		(10 "In4.Cu" signal "L5")
		(12 "In5.Cu" signal "L6GND")
		(14 "In6.Cu" signal "L7VCC")
		(16 "In7.Cu" signal "L8VCC")
		(18 "In8.Cu" signal "L9GND")
		(20 "In9.Cu" signal "L10")
		(22 "In10.Cu" signal "L11GND")
		(24 "In11.Cu" signal "L12")
		(26 "In12.Cu" signal "L13GND")
		(2 "B.Cu" signal "BOTTOM")
		(9 "F.Adhes" user "F.Adhesive")
		(11 "B.Adhes" user "B.Adhesive")
		(13 "F.Paste" user "Package Geometry/Pastemask Top")
		(15 "B.Paste" user "Package Geometry/Pastemask Bottom")
		(5 "F.SilkS" user "Ref Des/Silkscreen Top")
		(7 "B.SilkS" user "Ref Des/Silkscreen Bottom")
		(1 "F.Mask" user "Board Geometry/Soldermask Top")
		(3 "B.Mask" user "Board Geometry/Soldermask Bottom")
		(17 "Dwgs.User" user "User.Drawings")
		(19 "Cmts.User" user "User.Comments")
		(21 "Eco1.User" user "User.Eco1")
		(23 "Eco2.User" user "User.Eco2")
		(25 "Edge.Cuts" user "Board Geometry/Outline")
		(27 "Margin" user)
		(31 "F.CrtYd" user "Package Geometry/Place Bound Top")
		(29 "B.CrtYd" user "Package Geometry/Place Bound Bottom")
		(35 "F.Fab" user "Ref Des/Assembly Top")
		(33 "B.Fab" user "Ref Des/Assembly Bottom")
	)
	(footprint ""
		(layer "B.Cu")
		(at 178.562 -54.991 -90)
		(property "Reference" "C6R8"
			(at 0 0 90)
			(layer "B.SilkS")
			(hide yes)
			(effects
				(font
					(size 1.27 1.27)
				)
				(justify mirror)
			)
		)
		(property "Value" ""
			(at 0 0 90)
			(layer "B.Fab")
			(effects
				(font
					(size 1.27 1.27)
				)
				(justify mirror)
			)
		)
		(duplicate_pad_numbers_are_jumpers no)
		(fp_poly
			(pts
				(xy 0.7239 -0.2159) (xy -0.7239 -0.2159) (xy -0.7239 1.9939) (xy 0.7239 1.9939)
			)
			(stroke
				(width 0)
				(type default)
			)
			(fill no)
			(layer "B.CrtYd")
		)
		(fp_line
			(start -0.7239 1.9939)
			(end -0.7239 -0.2159)
			(stroke
				(width 0.1)
				(type default)
			)
			(layer "B.Fab")
		)
		(fp_line
			(start 0.7239 1.9939)
			(end -0.7239 1.9939)
			(stroke
				(width 0.1)
				(type default)
			)
			(layer "B.Fab")
		)
		(fp_line
			(start -0.7239 -0.2159)
			(end 0.7239 -0.2159)
			(stroke
				(width 0.1)
				(type default)
			)
			(layer "B.Fab")
		)
		(fp_line
			(start 0.7239 -0.2159)
			(end 0.7239 1.9939)
			(stroke
				(width 0.1)
				(type default)
			)
			(layer "B.Fab")
		)
		(pad "1" smd rect
			(at 0 0 90)
			(size 1.27 1.016)
			(layers "B.Cu" "B.Mask" "B.Paste")
			(net "VR_FET_SW_P12V_STBY_PVCCIN_CPU0")
		)
		(pad "2" smd rect
			(at 0 1.778 90)
			(size 1.27 1.016)
			(layers "B.Cu" "B.Mask" "B.Paste")
			(net "GND")
		)
		(zone
			(layer "B.Cu")
			(hatch none 0.5)
			(connect_pads
				(clearance 0)
			)
			(min_thickness 0.25)
			(keepout
				(tracks not_allowed)
				(vias allowed)
				(pads allowed)
				(copperpour not_allowed)
				(footprints allowed)
			)
			(placement
				(enabled no)
				(sheetname "")
			)
			(fill
				(thermal_gap 0.5)
				(thermal_bridge_width 0.5)
				(island_removal_mode 0)
			)
			(polygon
				(pts
					(xy 178.054 -54.356) (xy 178.054 -55.626) (xy 177.292 -55.626) (xy 177.292 -54.356)
				)
			)
		)
	)
	(footprint ""
		(layer "B.Cu")
		(at 80.757268 -17.7546 -90)
		(property "Reference" "C8T10"
			(at -1.848866 0.752348 270)
			(unlocked yes)
			(layer "B.SilkS")
			(effects
				(font
					(size 1.27 0.9652)
					(thickness 0.1524)
				)
				(justify mirror)
			)
		)
		(property "Value" ""
			(at 0 0 90)
			(layer "B.Fab")
			(effects
				(font
					(size 1.27 1.27)
				)
				(justify mirror)
			)
		)
		(duplicate_pad_numbers_are_jumpers no)
		(fp_rect
			(start 0.500126 1.598422)
			(end -0.500126 -0.201422)
			(stroke
				(width 0)
				(type default)
			)
			(fill no)
			(layer "B.CrtYd")
		)
		(fp_line
			(start -0.500126 1.598422)
			(end 0.500126 1.598422)
			(stroke
				(width 0.1)
				(type default)
			)
			(layer "B.Fab")
		)
		(fp_line
			(start 0.500126 1.598422)
			(end 0.500126 -0.201422)
			(stroke
				(width 0.1)
				(type default)
			)
			(layer "B.Fab")
		)
		(fp_line
			(start -0.500126 -0.201422)
			(end -0.500126 1.598422)
			(stroke
				(width 0.1)
				(type default)
			)
			(layer "B.Fab")
		)
		(fp_line
			(start 0.500126 -0.201422)
			(end -0.500126 -0.201422)
			(stroke
				(width 0.1)
				(type default)
			)
			(layer "B.Fab")
		)
		(pad "1" smd rect
			(at 0 0 180)
			(size 0.889 0.9906)
			(layers "B.Cu" "B.Mask" "B.Paste")
			(net "PVDDQ_GHJ")
		)
		(pad "2" smd rect
			(at 0 1.397 180)
			(size 0.889 0.9906)
			(layers "B.Cu" "B.Mask" "B.Paste")
			(net "GND")
		)
		(zone
			(layer "B.Cu")
			(hatch none 0.5)
			(connect_pads
				(clearance 0)
			)
			(min_thickness 0.25)
			(keepout
				(tracks not_allowed)
				(vias allowed)
				(pads allowed)
				(copperpour not_allowed)
				(footprints allowed)
			)
			(placement
				(enabled no)
				(sheetname "")
			)
			(fill
				(thermal_gap 0.5)
				(thermal_bridge_width 0.5)
				(island_removal_mode 0)
			)
			(polygon
				(pts
					(xy 79.804768 -17.2593) (xy 80.312768 -17.2593) (xy 80.312768 -18.2499) (xy 79.804768 -18.2499)
				)
			)
		)
		(zone
			(layer "B.Cu")
			(hatch none 0.5)
			(connect_pads
				(clearance 0)
			)
			(min_thickness 0.25)
			(keepout
				(tracks allowed)
				(vias not_allowed)
				(pads allowed)
				(copperpour not_allowed)
				(footprints allowed)
			)
			(placement
				(enabled no)
				(sheetname "")
			)
			(fill
				(thermal_gap 0.5)
				(thermal_bridge_width 0.5)
				(island_removal_mode 0)
			)
			(polygon
				(pts
					(xy 79.804768 -17.2593) (xy 80.312768 -17.2593) (xy 80.312768 -18.2499) (xy 79.804768 -18.2499)
				)
			)
		)
	)
	(footprint ""
		(layer "B.Cu")
		(at 32.832802 -66.425064 90)
		(property "Reference" "C9P25"
			(at 0 0 90)
			(layer "B.SilkS")
			(hide yes)
			(effects
				(font
					(size 1.27 1.27)
				)
				(justify mirror)
			)
		)
		(property "Value" ""
			(at 0 0 90)
			(layer "B.Fab")
			(effects
				(font
					(size 1.27 1.27)
				)
				(justify mirror)
			)
		)
		(duplicate_pad_numbers_are_jumpers no)
		(fp_poly
			(pts
				(xy 0.7239 -0.2159) (xy -0.7239 -0.2159) (xy -0.7239 1.9939) (xy 0.7239 1.9939)
			)
			(stroke
				(width 0)
				(type default)
			)
			(fill no)
			(layer "B.CrtYd")
		)
		(fp_line
			(start 0.7239 -0.2159)
			(end 0.7239 1.9939)
			(stroke
				(width 0.1)
				(type default)
			)
			(layer "B.Fab")
		)
		(fp_line
			(start -0.7239 -0.2159)
			(end 0.7239 -0.2159)
			(stroke
				(width 0.1)
				(type default)
			)
			(layer "B.Fab")
		)
		(fp_line
			(start 0.7239 1.9939)
			(end -0.7239 1.9939)
			(stroke
				(width 0.1)
				(type default)
			)
			(layer "B.Fab")
		)
		(fp_line
			(start -0.7239 1.9939)
			(end -0.7239 -0.2159)
			(stroke
				(width 0.1)
				(type default)
			)
			(layer "B.Fab")
		)
		(pad "1" smd rect
			(at 0 0 270)
			(size 1.27 1.016)
			(layers "B.Cu" "B.Mask" "B.Paste")
			(net "VR_FET_SW_P12V_STBY_PVCCIN_CPU1")
		)
		(pad "2" smd rect
			(at 0 1.778 270)
			(size 1.27 1.016)
			(layers "B.Cu" "B.Mask" "B.Paste")
			(net "GND")
		)
		(zone
			(layer "B.Cu")
			(hatch none 0.5)
			(connect_pads
				(clearance 0)
			)
			(min_thickness 0.25)
			(keepout
				(tracks not_allowed)
				(vias allowed)
				(pads allowed)
				(copperpour not_allowed)
				(footprints allowed)
			)
			(placement
				(enabled no)
				(sheetname "")
			)
			(fill
				(thermal_gap 0.5)
				(thermal_bridge_width 0.5)
				(island_removal_mode 0)
			)
			(polygon
				(pts
					(xy 33.340802 -67.060064) (xy 33.340802 -65.790064) (xy 34.102802 -65.790064) (xy 34.102802 -67.060064)
				)
			)
		)
	)
)
